# S9S_MB_2U (Grand Teton) — schematic netlist excerpt (pin names and nets, part order shuffled) for the footprints in the layout excerpt that follows; sources: Cadence DE-HDL packaged netlist, KiCad conversion of 03242023_DA0F0TMBIJ0_F0T_Motherboard_J_brd_V01_OCP.brd

R4562  Q_RES  100K 1% EMPTY  pkg 0402LF  page 146 : A = P3V3_AUX ; B = SWB_HSC_PWRGD

U87  MOSFET_N  BSS138K IC  pkg SMLF  page 134
  DRAIN  = P1V05_PCH_AUX
  GATE  = FM_REMOTE_DEBUG_DET_R
  SOURCE  = FM_BMC_EN_DET

PR1336  Q_RES  9.76K 1% CHIP  pkg 0402LF  page 281 : A = PVPP_HBM_CPU0_CS ; B = GND

(kicad_pcb
	(version 20260206)
	(generator "pcbnew")
	(generator_version "10.0")
	(general
		(thickness 1.6)
		(legacy_teardrops no)
	)
	(paper "A4")
	(title_block
		(title "03242023_DA0F0TMBIJ0_F0T_Motherboard_J_brd_V01_OCP.brd")
		(comment 1 "Grand Teton / footprints 1295-1297 of 6105")
	)
	(layers
		(0 "F.Cu" signal "TOP")
		(4 "In1.Cu" signal "GND")
		(6 "In2.Cu" signal "IN1")
		(8 "In3.Cu" signal "GND1")
		(10 "In4.Cu" signal "IN2")
		(12 "In5.Cu" signal "GND2")
		(14 "In6.Cu" signal "IN3")
		(16 "In7.Cu" signal "GND3")
		(18 "In8.Cu" signal "VCC")
		(20 "In9.Cu" signal "VCC1")
		(22 "In10.Cu" signal "GND4")
		(24 "In11.Cu" signal "IN4")
		(26 "In12.Cu" signal "GND5")
		(28 "In13.Cu" signal "IN5")
		(30 "In14.Cu" signal "GND6")
		(32 "In15.Cu" signal "IN6")
		(34 "In16.Cu" signal "GND7")
		(2 "B.Cu" signal "BOTTOM")
		(9 "F.Adhes" user "F.Adhesive")
		(11 "B.Adhes" user "B.Adhesive")
		(13 "F.Paste" user "Package Geometry/Pastemask Top")
		(15 "B.Paste" user "Package Geometry/Pastemask Bottom")
		(5 "F.SilkS" user "Ref Des/Silkscreen Top")
		(7 "B.SilkS" user "Ref Des/Silkscreen Bottom")
		(1 "F.Mask" user "Board Geometry/Soldermask Top")
		(3 "B.Mask" user "Board Geometry/Soldermask Bottom")
		(17 "Dwgs.User" user "User.Drawings")
		(19 "Cmts.User" user "User.Comments")
		(21 "Eco1.User" user "User.Eco1")
		(23 "Eco2.User" user "User.Eco2")
		(25 "Edge.Cuts" user "Board Geometry/Outline")
		(27 "Margin" user)
		(31 "F.CrtYd" user "Package Geometry/Place Bound Top")
		(29 "B.CrtYd" user "Package Geometry/Place Bound Bottom")
		(35 "F.Fab" user "Ref Des/Assembly Top")
		(33 "B.Fab" user "Ref Des/Assembly Bottom")
	)
	(footprint ""
		(layer "F.Cu")
		(at 93.27388 -56.225948)
		(property "Reference" "U87"
			(at -1.4224 -2.327148 0)
			(unlocked yes)
			(layer "F.SilkS")
			(effects
				(font
					(size 0.7874 0.5842)
					(thickness 0.1524)
				)
			)
		)
		(property "Value" ""
			(at 0 0 0)
			(layer "F.Fab")
			(effects
				(font
					(size 1.27 1.27)
				)
			)
		)
		(duplicate_pad_numbers_are_jumpers no)
		(fp_line
			(start -1.949958 -1.610106)
			(end 1.949958 -1.610106)
			(stroke
				(width 0.1524)
				(type default)
			)
			(layer "F.SilkS")
		)
		(fp_line
			(start -1.949958 1.610106)
			(end -1.949958 -1.610106)
			(stroke
				(width 0.1524)
				(type default)
			)
			(layer "F.SilkS")
		)
		(fp_line
			(start 1.949958 -1.560068)
			(end 1.949958 1.610106)
			(stroke
				(width 0.1524)
				(type default)
			)
			(layer "F.SilkS")
		)
		(fp_line
			(start 1.949958 1.610106)
			(end -1.949958 1.610106)
			(stroke
				(width 0.1524)
				(type default)
			)
			(layer "F.SilkS")
		)
		(fp_line
			(start -0.750062 -1.560068)
			(end 0.750062 -1.560068)
			(stroke
				(width 0.1)
				(type default)
			)
			(layer "F.Fab")
		)
		(fp_line
			(start -0.750062 1.560068)
			(end -0.750062 -1.560068)
			(stroke
				(width 0.1)
				(type default)
			)
			(layer "F.Fab")
		)
		(fp_line
			(start 0.750062 -1.560068)
			(end 0.750062 1.560068)
			(stroke
				(width 0.1)
				(type default)
			)
			(layer "F.Fab")
		)
		(fp_line
			(start 0.750062 1.560068)
			(end -0.750062 1.560068)
			(stroke
				(width 0.1)
				(type default)
			)
			(layer "F.Fab")
		)
		(pad "D" smd rect
			(at 1.100074 0 270)
			(size 1.016 1.4224)
			(layers "F.Cu" "F.Mask" "F.Paste")
			(net "P1V05_PCH_AUX")
		)
		(pad "G" smd rect
			(at -1.100074 -0.94996 270)
			(size 1.016 1.4224)
			(layers "F.Cu" "F.Mask" "F.Paste")
			(net "FM_REMOTE_DEBUG_DET_R")
		)
		(pad "S" smd rect
			(at -1.100074 0.94996 270)
			(size 1.016 1.4224)
			(layers "F.Cu" "F.Mask" "F.Paste")
			(net "FM_BMC_EN_DET")
		)
	)
	(footprint ""
		(layer "F.Cu")
		(at 356.616 -416.143948)
		(property "Reference" "R4562"
			(at 0 0 0)
			(layer "F.SilkS")
			(hide yes)
			(effects
				(font
					(size 1.27 1.27)
				)
			)
		)
		(property "Value" ""
			(at 0 0 0)
			(layer "F.Fab")
			(effects
				(font
					(size 1.27 1.27)
				)
			)
		)
		(duplicate_pad_numbers_are_jumpers no)
		(fp_line
			(start -0.7874 -0.4064)
			(end 0.7874 -0.4064)
			(stroke
				(width 0.1524)
				(type default)
			)
			(layer "F.SilkS")
		)
		(fp_line
			(start -0.7874 0.4064)
			(end -0.7874 -0.4064)
			(stroke
				(width 0.1524)
				(type default)
			)
			(layer "F.SilkS")
		)
		(fp_line
			(start 0.7874 -0.4064)
			(end 0.7874 0.4064)
			(stroke
				(width 0.1524)
				(type default)
			)
			(layer "F.SilkS")
		)
		(fp_line
			(start 0.7874 0.4064)
			(end -0.7874 0.4064)
			(stroke
				(width 0.1524)
				(type default)
			)
			(layer "F.SilkS")
		)
		(fp_line
			(start -0.67945 -0.305054)
			(end -0.12065 -0.305054)
			(stroke
				(width 0.1)
				(type default)
			)
			(layer "F.Fab")
		)
		(fp_line
			(start -0.67945 0.3048)
			(end -0.67945 -0.305054)
			(stroke
				(width 0.1)
				(type default)
			)
			(layer "F.Fab")
		)
		(fp_line
			(start -0.12065 -0.305054)
			(end -0.12065 -0.2794)
			(stroke
				(width 0.1)
				(type default)
			)
			(layer "F.Fab")
		)
		(fp_line
			(start -0.12065 -0.2794)
			(end 0.12065 -0.2794)
			(stroke
				(width 0.1)
				(type default)
			)
			(layer "F.Fab")
		)
		(fp_line
			(start -0.12065 0.2794)
			(end -0.12065 0.3048)
			(stroke
				(width 0.1)
				(type default)
			)
			(layer "F.Fab")
		)
		(fp_line
			(start -0.12065 0.3048)
			(end -0.67945 0.3048)
			(stroke
				(width 0.1)
				(type default)
			)
			(layer "F.Fab")
		)
		(fp_line
			(start 0.120396 0.2794)
			(end -0.12065 0.2794)
			(stroke
				(width 0.1)
				(type default)
			)
			(layer "F.Fab")
		)
		(fp_line
			(start 0.120396 0.3048)
			(end 0.120396 0.2794)
			(stroke
				(width 0.1)
				(type default)
			)
			(layer "F.Fab")
		)
		(fp_line
			(start 0.12065 -0.3048)
			(end 0.67945 -0.3048)
			(stroke
				(width 0.1)
				(type default)
			)
			(layer "F.Fab")
		)
		(fp_line
			(start 0.12065 -0.2794)
			(end 0.12065 -0.3048)
			(stroke
				(width 0.1)
				(type default)
			)
			(layer "F.Fab")
		)
		(fp_line
			(start 0.67945 -0.3048)
			(end 0.67945 0.3048)
			(stroke
				(width 0.1)
				(type default)
			)
			(layer "F.Fab")
		)
		(fp_line
			(start 0.67945 0.3048)
			(end 0.120396 0.3048)
			(stroke
				(width 0.1)
				(type default)
			)
			(layer "F.Fab")
		)
		(pad "1" smd circle
			(at -0.40005 0)
			(size 0 0)
			(layers "F.Cu" "F.Mask" "F.Paste")
			(net "P3V3_AUX")
		)
		(pad "2" smd circle
			(at 0.40005 0)
			(size 0 0)
			(layers "F.Cu" "F.Mask" "F.Paste")
			(net "SWB_HSC_PWRGD")
		)
	)
	(footprint ""
		(layer "F.Cu")
		(at 369.923822 -360.043222 90)
		(property "Reference" "PR1336"
			(at 0 0 90)
			(layer "F.SilkS")
			(hide yes)
			(effects
				(font
					(size 1.27 1.27)
				)
			)
		)
		(property "Value" ""
			(at 0 0 90)
			(layer "F.Fab")
			(effects
				(font
					(size 1.27 1.27)
				)
			)
		)
		(duplicate_pad_numbers_are_jumpers no)
		(fp_line
			(start 0.7874 -0.4064)
			(end 0.7874 0.4064)
			(stroke
				(width 0.1524)
				(type default)
			)
			(layer "F.SilkS")
		)
		(fp_line
			(start -0.7874 -0.4064)
			(end 0.7874 -0.4064)
			(stroke
				(width 0.1524)
				(type default)
			)
			(layer "F.SilkS")
		)
		(fp_line
			(start 0.7874 0.4064)
			(end -0.7874 0.4064)
			(stroke
				(width 0.1524)
				(type default)
			)
			(layer "F.SilkS")
		)
		(fp_line
			(start -0.7874 0.4064)
			(end -0.7874 -0.4064)
			(stroke
				(width 0.1524)
				(type default)
			)
			(layer "F.SilkS")
		)
		(fp_line
			(start -0.12065 -0.305054)
			(end -0.12065 -0.2794)
			(stroke
				(width 0.1)
				(type default)
			)
			(layer "F.Fab")
		)
		(fp_line
			(start -0.67945 -0.305054)
			(end -0.12065 -0.305054)
			(stroke
				(width 0.1)
				(type default)
			)
			(layer "F.Fab")
		)
		(fp_line
			(start 0.67945 -0.3048)
			(end 0.67945 0.3048)
			(stroke
				(width 0.1)
				(type default)
			)
			(layer "F.Fab")
		)
		(fp_line
			(start 0.12065 -0.3048)
			(end 0.67945 -0.3048)
			(stroke
				(width 0.1)
				(type default)
			)
			(layer "F.Fab")
		)
		(fp_line
			(start 0.12065 -0.2794)
			(end 0.12065 -0.3048)
			(stroke
				(width 0.1)
				(type default)
			)
			(layer "F.Fab")
		)
		(fp_line
			(start -0.12065 -0.2794)
			(end 0.12065 -0.2794)
			(stroke
				(width 0.1)
				(type default)
			)
			(layer "F.Fab")
		)
		(fp_line
			(start 0.120396 0.2794)
			(end -0.12065 0.2794)
			(stroke
				(width 0.1)
				(type default)
			)
			(layer "F.Fab")
		)
		(fp_line
			(start -0.12065 0.2794)
			(end -0.12065 0.3048)
			(stroke
				(width 0.1)
				(type default)
			)
			(layer "F.Fab")
		)
		(fp_line
			(start 0.67945 0.3048)
			(end 0.120396 0.3048)
			(stroke
				(width 0.1)
				(type default)
			)
			(layer "F.Fab")
		)
		(fp_line
			(start 0.120396 0.3048)
			(end 0.120396 0.2794)
			(stroke
				(width 0.1)
				(type default)
			)
			(layer "F.Fab")
		)
		(fp_line
			(start -0.12065 0.3048)
			(end -0.67945 0.3048)
			(stroke
				(width 0.1)
				(type default)
			)
			(layer "F.Fab")
		)
		(fp_line
			(start -0.67945 0.3048)
			(end -0.67945 -0.305054)
			(stroke
				(width 0.1)
				(type default)
			)
			(layer "F.Fab")
		)
		(pad "1" smd circle
			(at -0.40005 0 90)
			(size 0 0)
			(layers "F.Cu" "F.Mask" "F.Paste")
			(net "PVPP_HBM_CPU0_CS")
		)
		(pad "2" smd circle
			(at 0.40005 0 90)
			(size 0 0)
			(layers "F.Cu" "F.Mask" "F.Paste")
			(net "GND")
		)
	)
)
